(kicad_pcb
	(version 20260206)
	(generator "pcbnew")
	(generator_version "10.0")
	(general
		(thickness 1.6)
		(legacy_teardrops no)
	)
	(paper "A4")
	(title_block
		(title "v1-pdb — T6M_PDB_D_0927_0900.brd")
		(comment 1 "Open CloudServer (Microsoft) / footprints 172-179 of 321")
	)
	(layers
		(0 "F.Cu" signal "TOP")
		(4 "In1.Cu" signal "GND")
		(6 "In2.Cu" signal "IN1")
		(8 "In3.Cu" signal "VCC")
		(10 "In4.Cu" signal "VCC1")
		(12 "In5.Cu" signal "IN2")
		(14 "In6.Cu" signal "GND1")
		(2 "B.Cu" signal "BOTTOM")
		(9 "F.Adhes" user "F.Adhesive")
		(11 "B.Adhes" user "B.Adhesive")
		(13 "F.Paste" user "Package Geometry/Pastemask Top")
		(15 "B.Paste" user "Package Geometry/Pastemask Bottom")
		(5 "F.SilkS" user "Ref Des/Silkscreen Top")
		(7 "B.SilkS" user "Ref Des/Silkscreen Bottom")
		(1 "F.Mask" user "Board Geometry/Soldermask Top")
		(3 "B.Mask" user "Board Geometry/Soldermask Bottom")
		(17 "Dwgs.User" user "User.Drawings")
		(19 "Cmts.User" user "User.Comments")
		(21 "Eco1.User" user "User.Eco1")
		(23 "Eco2.User" user "User.Eco2")
		(25 "Edge.Cuts" user "Board Geometry/Outline")
		(27 "Margin" user)
		(31 "F.CrtYd" user "Package Geometry/Place Bound Top")
		(29 "B.CrtYd" user "Package Geometry/Place Bound Bottom")
		(35 "F.Fab" user "Ref Des/Assembly Top")
		(33 "B.Fab" user "Ref Des/Assembly Bottom")
	)
	(footprint ""
		(layer "F.Cu")
		(at 97.946464 -505.85878)
		(property "Reference" ""
			(at 0 0 0)
			(layer "F.SilkS")
			(hide yes)
			(effects
				(font
					(size 1.27 1.27)
				)
			)
		)
		(property "Value" ""
			(at 0 0 0)
			(layer "F.Fab")
			(effects
				(font
					(size 1.27 1.27)
				)
			)
		)
		(duplicate_pad_numbers_are_jumpers no)
		(fp_poly
			(pts
				(arc
					(start 1.4986 0)
					(mid -1.4986 0)
					(end 1.4986 0)
				)
			)
			(stroke
				(width 0)
				(type default)
			)
			(fill no)
			(layer "F.CrtYd")
		)
		(pad "1" smd circle
			(at 0 0)
			(size 0.9906 0.9906)
			(layers "F.Cu" "F.Mask" "F.Paste")
			(net "Net_171")
		)
		(zone
			(layer "F.Cu")
			(hatch none 0.5)
			(connect_pads
				(clearance 0)
			)
			(min_thickness 0.25)
			(keepout
				(tracks not_allowed)
				(vias allowed)
				(pads allowed)
				(copperpour not_allowed)
				(footprints allowed)
			)
			(placement
				(enabled no)
				(sheetname "")
			)
			(fill
				(thermal_gap 0.5)
				(thermal_bridge_width 0.5)
				(island_removal_mode 0)
			)
			(polygon
				(pts
					(arc
						(start 99.572064 -505.85878)
						(mid 96.320864 -505.85878)
						(end 99.572064 -505.85878)
					)
				)
			)
		)
	)
	(footprint ""
		(layer "F.Cu")
		(at 50.217324 -173.13783 180)
		(property "Reference" "CE9"
			(at 0.06858 -5.780024 0)
			(unlocked yes)
			(layer "F.SilkS")
			(effects
				(font
					(size 0.7874 0.5842)
					(thickness 0.1524)
				)
				(justify left)
			)
		)
		(property "Value" ""
			(at 0 0 180)
			(layer "F.Fab")
			(effects
				(font
					(size 1.27 1.27)
				)
			)
		)
		(duplicate_pad_numbers_are_jumpers no)
		(fp_line
			(start 0 -4.2672)
			(end 0 4.2672)
			(stroke
				(width 0.1524)
				(type default)
			)
			(layer "F.SilkS")
		)
		(fp_circle
			(center 0 0)
			(end -4.2672 0)
			(stroke
				(width 0.1524)
				(type default)
			)
			(fill no)
			(layer "F.SilkS")
		)
		(fp_poly
			(pts
				(arc
					(start 0 -4.2672)
					(mid 4.2672 0)
					(end 0 4.2672)
				)
			)
			(stroke
				(width 0)
				(type default)
			)
			(fill yes)
			(layer "F.SilkS")
		)
		(fp_poly
			(pts
				(xy -2.5146 -0.762) (xy -0.9906 -0.762) (xy -0.9906 0.762) (xy -2.5146 0.762)
			)
			(stroke
				(width 0)
				(type default)
			)
			(fill no)
			(layer "B.CrtYd")
		)
		(fp_poly
			(pts
				(arc
					(start 1.7526 0.762)
					(mid 2.291415 -0.538815)
					(end 0.9906 0)
				)
				(arc
					(start 0.9906 0.0254)
					(mid 1.206345 0.546255)
					(end 1.7272 0.762)
				)
			)
			(stroke
				(width 0)
				(type default)
			)
			(fill no)
			(layer "B.CrtYd")
		)
		(fp_poly
			(pts
				(arc
					(start -4.2672 0)
					(mid 4.2672 0)
					(end -4.2672 0)
				)
			)
			(stroke
				(width 0)
				(type default)
			)
			(fill no)
			(layer "F.CrtYd")
		)
		(fp_circle
			(center 0 0)
			(end -4.2672 0)
			(stroke
				(width 0.1)
				(type default)
			)
			(fill no)
			(layer "F.Fab")
		)
		(fp_text user "+"
			(at -4.90728 1.70053 180)
			(unlocked yes)
			(layer "F.SilkS")
			(effects
				(font
					(size 0.7874 0.5842)
					(thickness 0.1524)
				)
				(justify left)
			)
		)
		(fp_text user "+"
			(at -5.6642 -0.34925 180)
			(unlocked yes)
			(layer "F.Fab")
			(effects
				(font
					(size 1.905 1.4224)
					(thickness 0.000001)
				)
				(justify left)
			)
		)
		(pad "1" thru_hole rect
			(at -1.75006 0 180)
			(size 1.397 1.397)
			(drill 0.9144)
			(layers "*.Cu" "*.Mask")
			(remove_unused_layers no)
			(net "P12V")
			(clearance 0.0127)
			(thermal_gap 0.0127)
			(padstack
				(mode front_inner_back)
				(layer "Inner"
					(shape circle)
					(size 1.397 1.397)
					(clearance 0.0127)
				)
				(layer "B.Cu"
					(shape rect)
					(size 1.397 1.397)
					(clearance 0.0127)
				)
			)
		)
		(pad "2" thru_hole circle
			(at 1.75006 0 180)
			(size 1.397 1.397)
			(drill 0.9144)
			(layers "*.Cu" "*.Mask")
			(remove_unused_layers no)
			(net "GND")
			(clearance 0.0127)
			(thermal_gap 0.0127)
		)
	)
	(footprint ""
		(layer "F.Cu")
		(at 91.399868 -197.81012)
		(property "Reference" "H20"
			(at -5.1308 -5.23113 0)
			(unlocked yes)
			(layer "F.SilkS")
			(effects
				(font
					(size 0.7874 0.5842)
					(thickness 0.1524)
				)
				(justify left)
			)
		)
		(property "Value" ""
			(at 0 0 0)
			(layer "F.Fab")
			(effects
				(font
					(size 1.27 1.27)
				)
			)
		)
		(duplicate_pad_numbers_are_jumpers no)
		(fp_circle
			(center 0 0)
			(end 4.826 0)
			(stroke
				(width 0.1524)
				(type default)
			)
			(fill no)
			(layer "F.SilkS")
		)
		(fp_circle
			(center 0 0)
			(end 4.826 0)
			(stroke
				(width 0.1524)
				(type default)
			)
			(fill no)
			(layer "B.SilkS")
		)
		(fp_poly
			(pts
				(arc
					(start 0 4.0132)
					(mid 0 -4.0132)
					(end 0 4.0132)
				)
			)
			(stroke
				(width 0)
				(type default)
			)
			(fill no)
			(layer "F.CrtYd")
		)
		(pad "" np_thru_hole circle
			(at 0 0)
			(size 8.001 8.001)
			(drill 8.001)
			(layers "*.Cu" "*.Mask")
			(clearance 0.381)
			(thermal_gap 0.381)
		)
		(zone
			(layers "F.Cu" "B.Cu" "In1.Cu" "In2.Cu" "In3.Cu" "In4.Cu" "In5.Cu" "In6.Cu")
			(hatch none 0.5)
			(connect_pads
				(clearance 0)
			)
			(min_thickness 0.25)
			(keepout
				(tracks not_allowed)
				(vias allowed)
				(pads allowed)
				(copperpour not_allowed)
				(footprints allowed)
			)
			(placement
				(enabled no)
				(sheetname "")
			)
			(fill
				(thermal_gap 0.5)
				(thermal_bridge_width 0.5)
				(island_removal_mode 0)
			)
			(polygon
				(pts
					(arc
						(start 91.399868 -193.28892)
						(mid 91.399868 -202.33132)
						(end 91.399868 -193.28892)
					)
				)
			)
		)
	)
	(footprint ""
		(layer "F.Cu")
		(at 74.832718 -263.260078 90)
		(property "Reference" "C46"
			(at -4.410456 0.239268 90)
			(unlocked yes)
			(layer "F.SilkS")
			(effects
				(font
					(size 0.7874 0.5842)
					(thickness 0.1524)
				)
				(justify left)
			)
		)
		(property "Value" ""
			(at 0 0 90)
			(layer "F.Fab")
			(effects
				(font
					(size 1.27 1.27)
				)
			)
		)
		(duplicate_pad_numbers_are_jumpers no)
		(fp_line
			(start 0.7874 -0.4064)
			(end 0.7874 0.4064)
			(stroke
				(width 0.1524)
				(type default)
			)
			(layer "F.SilkS")
		)
		(fp_line
			(start -0.7874 -0.4064)
			(end 0.7874 -0.4064)
			(stroke
				(width 0.1524)
				(type default)
			)
			(layer "F.SilkS")
		)
		(fp_line
			(start 0 0.381)
			(end 0 -0.381)
			(stroke
				(width 0.1524)
				(type default)
			)
			(layer "F.SilkS")
		)
		(fp_line
			(start 0.7874 0.4064)
			(end -0.7874 0.4064)
			(stroke
				(width 0.1524)
				(type default)
			)
			(layer "F.SilkS")
		)
		(fp_line
			(start -0.7874 0.4064)
			(end -0.7874 -0.4064)
			(stroke
				(width 0.1524)
				(type default)
			)
			(layer "F.SilkS")
		)
		(fp_poly
			(pts
				(xy -0.5334 0.254) (xy -0.635 0.254) (xy -0.635 0.2286) (xy -0.635 -0.254) (xy -0.5334 -0.254) (xy -0.5334 -0.2794)
				(xy 0.5334 -0.2794) (xy 0.5334 -0.254) (xy 0.635 -0.254) (xy 0.635 0.254) (xy 0.5334 0.254) (xy 0.5334 0.2794)
				(xy -0.508 0.2794) (xy -0.5334 0.2794)
			)
			(stroke
				(width 0)
				(type default)
			)
			(fill no)
			(layer "F.CrtYd")
		)
		(pad "1" smd rect
			(at 0.40005 0 90)
			(size 0.4572 0.508)
			(layers "F.Cu" "F.Mask" "F.Paste")
			(net "P12V")
		)
		(pad "2" smd rect
			(at -0.40005 0 90)
			(size 0.4572 0.508)
			(layers "F.Cu" "F.Mask" "F.Paste")
			(net "GND")
		)
	)
	(footprint ""
		(layer "F.Cu")
		(at 2.81559 -395.443964 90)
		(property "Reference" "R152"
			(at -4.444746 0.160528 90)
			(unlocked yes)
			(layer "F.SilkS")
			(effects
				(font
					(size 0.7874 0.5842)
					(thickness 0.1524)
				)
				(justify left)
			)
		)
		(property "Value" ""
			(at 0 0 90)
			(layer "F.Fab")
			(effects
				(font
					(size 1.27 1.27)
				)
			)
		)
		(duplicate_pad_numbers_are_jumpers no)
		(fp_line
			(start 0.7874 -0.4064)
			(end 0.7874 0.4064)
			(stroke
				(width 0.1524)
				(type default)
			)
			(layer "F.SilkS")
		)
		(fp_line
			(start -0.7874 -0.4064)
			(end 0.7874 -0.4064)
			(stroke
				(width 0.1524)
				(type default)
			)
			(layer "F.SilkS")
		)
		(fp_line
			(start 0.7874 0.4064)
			(end -0.7874 0.4064)
			(stroke
				(width 0.1524)
				(type default)
			)
			(layer "F.SilkS")
		)
		(fp_line
			(start -0.7874 0.4064)
			(end -0.7874 -0.4064)
			(stroke
				(width 0.1524)
				(type default)
			)
			(layer "F.SilkS")
		)
		(fp_poly
			(pts
				(xy -0.508 0.2794) (xy -0.508 0.2286) (xy -0.635 0.2286) (xy -0.635 -0.254) (xy -0.5334 -0.254)
				(xy -0.5334 -0.2794) (xy 0.5334 -0.2794) (xy 0.5334 -0.254) (xy 0.635 -0.254) (xy 0.635 0.254) (xy 0.5334 0.254)
				(xy 0.5334 0.2794)
			)
			(stroke
				(width 0)
				(type default)
			)
			(fill no)
			(layer "F.CrtYd")
		)
		(pad "1" smd rect
			(at 0.40005 0 90)
			(size 0.4572 0.508)
			(layers "F.Cu" "F.Mask" "F.Paste")
			(net "N42132933")
		)
		(pad "2" smd rect
			(at -0.40005 0 90)
			(size 0.4572 0.508)
			(layers "F.Cu" "F.Mask" "F.Paste")
			(net "GND")
		)
	)
	(footprint ""
		(layer "F.Cu")
		(at 46.496478 -248.705116 180)
		(property "Reference" "R95"
			(at -0.92964 -0.866902 0)
			(unlocked yes)
			(layer "F.SilkS")
			(effects
				(font
					(size 0.7874 0.5842)
					(thickness 0.1524)
				)
				(justify left)
			)
		)
		(property "Value" ""
			(at 0 0 180)
			(layer "F.Fab")
			(effects
				(font
					(size 1.27 1.27)
				)
			)
		)
		(duplicate_pad_numbers_are_jumpers no)
		(fp_line
			(start 0.7874 0.4064)
			(end -0.7874 0.4064)
			(stroke
				(width 0.1524)
				(type default)
			)
			(layer "F.SilkS")
		)
		(fp_line
			(start 0.7874 -0.4064)
			(end 0.7874 0.4064)
			(stroke
				(width 0.1524)
				(type default)
			)
			(layer "F.SilkS")
		)
		(fp_line
			(start -0.7874 0.4064)
			(end -0.7874 -0.4064)
			(stroke
				(width 0.1524)
				(type default)
			)
			(layer "F.SilkS")
		)
		(fp_line
			(start -0.7874 -0.4064)
			(end 0.7874 -0.4064)
			(stroke
				(width 0.1524)
				(type default)
			)
			(layer "F.SilkS")
		)
		(fp_poly
			(pts
				(xy -0.508 0.2794) (xy -0.508 0.2286) (xy -0.635 0.2286) (xy -0.635 -0.254) (xy -0.5334 -0.254)
				(xy -0.5334 -0.2794) (xy 0.5334 -0.2794) (xy 0.5334 -0.254) (xy 0.635 -0.254) (xy 0.635 0.254) (xy 0.5334 0.254)
				(xy 0.5334 0.2794)
			)
			(stroke
				(width 0)
				(type default)
			)
			(fill no)
			(layer "F.CrtYd")
		)
		(pad "1" smd rect
			(at 0.40005 0 180)
			(size 0.4572 0.508)
			(layers "F.Cu" "F.Mask" "F.Paste")
			(net "PSU3_REMOTE_R_N")
		)
		(pad "2" smd rect
			(at -0.40005 0 180)
			(size 0.4572 0.508)
			(layers "F.Cu" "F.Mask" "F.Paste")
			(net "GND")
		)
	)
	(footprint ""
		(layer "F.Cu")
		(at 74.69886 -415.478722 -90)
		(property "Reference" "C66"
			(at -3.000502 0.051816 90)
			(unlocked yes)
			(layer "F.SilkS")
			(effects
				(font
					(size 0.7874 0.5842)
					(thickness 0.1524)
				)
				(justify left)
			)
		)
		(property "Value" ""
			(at 0 0 270)
			(layer "F.Fab")
			(effects
				(font
					(size 1.27 1.27)
				)
			)
		)
		(duplicate_pad_numbers_are_jumpers no)
		(fp_line
			(start -0.7874 0.4064)
			(end -0.7874 -0.4064)
			(stroke
				(width 0.1524)
				(type default)
			)
			(layer "F.SilkS")
		)
		(fp_line
			(start 0.7874 0.4064)
			(end -0.7874 0.4064)
			(stroke
				(width 0.1524)
				(type default)
			)
			(layer "F.SilkS")
		)
		(fp_line
			(start 0 0.381)
			(end 0 -0.381)
			(stroke
				(width 0.1524)
				(type default)
			)
			(layer "F.SilkS")
		)
		(fp_line
			(start -0.7874 -0.4064)
			(end 0.7874 -0.4064)
			(stroke
				(width 0.1524)
				(type default)
			)
			(layer "F.SilkS")
		)
		(fp_line
			(start 0.7874 -0.4064)
			(end 0.7874 0.4064)
			(stroke
				(width 0.1524)
				(type default)
			)
			(layer "F.SilkS")
		)
		(fp_poly
			(pts
				(xy -0.5334 0.254) (xy -0.635 0.254) (xy -0.635 0.2286) (xy -0.635 -0.254) (xy -0.5334 -0.254) (xy -0.5334 -0.2794)
				(xy 0.5334 -0.2794) (xy 0.5334 -0.254) (xy 0.635 -0.254) (xy 0.635 0.254) (xy 0.5334 0.254) (xy 0.5334 0.2794)
				(xy -0.508 0.2794) (xy -0.5334 0.2794)
			)
			(stroke
				(width 0)
				(type default)
			)
			(fill no)
			(layer "F.CrtYd")
		)
		(pad "1" smd rect
			(at 0.40005 0 270)
			(size 0.4572 0.508)
			(layers "F.Cu" "F.Mask" "F.Paste")
			(net "P12V")
		)
		(pad "2" smd rect
			(at -0.40005 0 270)
			(size 0.4572 0.508)
			(layers "F.Cu" "F.Mask" "F.Paste")
			(net "GND")
		)
	)
	(footprint ""
		(layer "F.Cu")
		(at 2.439924 -380.824994 90)
		(property "Reference" "J32"
			(at -1.722628 4.838954 90)
			(unlocked yes)
			(layer "F.SilkS")
			(effects
				(font
					(size 0.7874 0.5842)
					(thickness 0.1524)
				)
				(justify left)
			)
		)
		(property "Value" ""
			(at 0 0 90)
			(layer "F.Fab")
			(effects
				(font
					(size 1.27 1.27)
				)
			)
		)
		(duplicate_pad_numbers_are_jumpers no)
		(fp_line
			(start 1.849882 -1.999996)
			(end -3.02006 -1.999996)
			(stroke
				(width 0.1524)
				(type default)
			)
			(layer "F.SilkS")
		)
		(fp_line
			(start -3.02006 -1.999996)
			(end -3.02006 3.999992)
			(stroke
				(width 0.1524)
				(type default)
			)
			(layer "F.SilkS")
		)
		(fp_line
			(start 1.35001 -1.500124)
			(end -2.519934 -1.500124)
			(stroke
				(width 0.1524)
				(type default)
			)
			(layer "F.SilkS")
		)
		(fp_line
			(start -2.519934 -1.500124)
			(end -2.519934 3.50012)
			(stroke
				(width 0.1524)
				(type default)
			)
			(layer "F.SilkS")
		)
		(fp_line
			(start 1.849882 0.500126)
			(end 1.35001 0.500126)
			(stroke
				(width 0.1524)
				(type default)
			)
			(layer "F.SilkS")
		)
		(fp_line
			(start 1.35001 0.500126)
			(end 1.35001 -1.500124)
			(stroke
				(width 0.1524)
				(type default)
			)
			(layer "F.SilkS")
		)
		(fp_line
			(start 1.35001 1.500124)
			(end 1.849882 1.500124)
			(stroke
				(width 0.1524)
				(type default)
			)
			(layer "F.SilkS")
		)
		(fp_line
			(start 1.35001 3.50012)
			(end 1.35001 1.500124)
			(stroke
				(width 0.1524)
				(type default)
			)
			(layer "F.SilkS")
		)
		(fp_line
			(start -2.519934 3.50012)
			(end 1.35001 3.50012)
			(stroke
				(width 0.1524)
				(type default)
			)
			(layer "F.SilkS")
		)
		(fp_line
			(start 1.849882 3.999992)
			(end 1.849882 -1.999996)
			(stroke
				(width 0.1524)
				(type default)
			)
			(layer "F.SilkS")
		)
		(fp_line
			(start -3.02006 3.999992)
			(end 1.849882 3.999992)
			(stroke
				(width 0.1524)
				(type default)
			)
			(layer "F.SilkS")
		)
		(fp_poly
			(pts
				(xy 2.01041 0) (xy 3.06959 -0.52959) (xy 3.06959 0.52959)
			)
			(stroke
				(width 0)
				(type default)
			)
			(fill yes)
			(layer "F.SilkS")
		)
		(fp_poly
			(pts
				(xy -0.8382 2.8194) (xy 0.8382 2.8194) (xy 0.8382 -0.8382) (xy -0.8382 -0.8382)
			)
			(stroke
				(width 0)
				(type default)
			)
			(fill no)
			(layer "B.CrtYd")
		)
		(fp_poly
			(pts
				(xy -3.02006 3.999992) (xy 1.849882 3.999992) (xy 1.849882 -1.999996) (xy -3.02006 -1.999996)
			)
			(stroke
				(width 0)
				(type default)
			)
			(fill no)
			(layer "F.CrtYd")
		)
		(fp_line
			(start 1.849882 -1.999996)
			(end -3.02006 -1.999996)
			(stroke
				(width 0.1)
				(type default)
			)
			(layer "F.Fab")
		)
		(fp_line
			(start -3.02006 -1.999996)
			(end -3.02006 3.999992)
			(stroke
				(width 0.1)
				(type default)
			)
			(layer "F.Fab")
		)
		(fp_line
			(start 1.849882 3.999992)
			(end 1.849882 -1.999996)
			(stroke
				(width 0.1)
				(type default)
			)
			(layer "F.Fab")
		)
		(fp_line
			(start -3.02006 3.999992)
			(end 1.849882 3.999992)
			(stroke
				(width 0.1)
				(type default)
			)
			(layer "F.Fab")
		)
		(fp_poly
			(pts
				(xy 2.01041 0) (xy 3.06959 -0.52959) (xy 3.06959 0.52959)
			)
			(stroke
				(width 0)
				(type default)
			)
			(fill yes)
			(layer "F.Fab")
		)
		(fp_text user "2"
			(at 2.5527 2.16535 90)
			(unlocked yes)
			(layer "F.SilkS")
			(effects
				(font
					(size 0.7874 0.5842)
					(thickness 0.1524)
				)
			)
		)
		(fp_text user "1"
			(at 1.2192 0.00127 90)
			(unlocked yes)
			(layer "B.SilkS")
			(effects
				(font
					(size 0.7874 0.5842)
					(thickness 0.1524)
				)
				(justify mirror)
			)
		)
		(fp_text user "2"
			(at 1.2192 2.001266 90)
			(unlocked yes)
			(layer "B.SilkS")
			(effects
				(font
					(size 0.7874 0.5842)
					(thickness 0.1524)
				)
				(justify mirror)
			)
		)
		(fp_text user "1"
			(at 1.2192 0.00127 90)
			(unlocked yes)
			(layer "B.Fab")
			(effects
				(font
					(size 0.7874 0.5842)
					(thickness 0.1524)
				)
				(justify mirror)
			)
		)
		(fp_text user "2"
			(at 1.2192 2.001266 90)
			(unlocked yes)
			(layer "B.Fab")
			(effects
				(font
					(size 0.7874 0.5842)
					(thickness 0.1524)
				)
				(justify mirror)
			)
		)
		(fp_text user "2"
			(at 2.5527 2.16535 90)
			(unlocked yes)
			(layer "F.Fab")
			(effects
				(font
					(size 0.7874 0.5842)
					(thickness 0.1524)
				)
			)
		)
		(pad "1" thru_hole rect
			(at 0 0 90)
			(size 1.524 1.524)
			(drill 1.016)
			(layers "*.Cu" "*.Mask")
			(remove_unused_layers no)
			(net "POWER_SW1_PWR_CTR_12V")
			(clearance 0)
			(padstack
				(mode front_inner_back)
				(layer "Inner"
					(shape circle)
					(size 1.524 1.524)
					(clearance 0)
				)
				(layer "B.Cu"
					(shape rect)
					(size 1.524 1.524)
					(clearance 0)
				)
			)
		)
		(pad "2" thru_hole circle
			(at 0 1.999996 90)
			(size 1.524 1.524)
			(drill 1.016)
			(layers "*.Cu" "*.Mask")
			(remove_unused_layers no)
			(net "GND")
			(clearance 0)
		)
	)
)
